FILE_TYPE = CONNECTIVITY;
{Allegro Design Entry HDL 16.6-p007 (v16-6-112F) 10/10/2012}
"PAGE_NUMBER" = 258;
0"NC";
END.
